# SCM (Grand Teton) — schematic netlist excerpt (pin names and nets, part order shuffled) for the footprints in the layout excerpt that follows; sources: Cadence DE-HDL packaged netlist, KiCad conversion of 12092022_DA0F0TMDCD0_F0T_Management_Board_D_brd_V3_OCP.brd

R54  Q_RES  10K 1% CHIP  pkg 0402LF  page 26 : A = SMB_BMC_ALERT16_R_N ; B = SMB_BMC_ALERT16_N
C175  Q_CAP  0.1UF 25V 10% X7R  pkg 0402  page 30 : A = P3V3_AUX ; B = GND

(kicad_pcb
	(version 20260206)
	(generator "pcbnew")
	(generator_version "10.0")
	(general
		(thickness 1.6)
		(legacy_teardrops no)
	)
	(paper "A4")
	(title_block
		(title "12092022_DA0F0TMDCD0_F0T_Management_Board_D_brd_V3_OCP.brd")
		(comment 1 "Grand Teton / footprints 1289-1290 of 1440")
	)
	(layers
		(0 "F.Cu" signal "TOP")
		(4 "In1.Cu" signal "GND")
		(6 "In2.Cu" signal "IN1")
		(8 "In3.Cu" signal "GND1")
		(10 "In4.Cu" signal "IN2")
		(12 "In5.Cu" signal "VCC")
		(14 "In6.Cu" signal "VCC1")
		(16 "In7.Cu" signal "IN3")
		(18 "In8.Cu" signal "GND2")
		(20 "In9.Cu" signal "IN4")
		(22 "In10.Cu" signal "GND3")
		(2 "B.Cu" signal "BOTTOM")
		(9 "F.Adhes" user "F.Adhesive")
		(11 "B.Adhes" user "B.Adhesive")
		(13 "F.Paste" user "Package Geometry/Pastemask Top")
		(15 "B.Paste" user "Package Geometry/Pastemask Bottom")
		(5 "F.SilkS" user "Ref Des/Silkscreen Top")
		(7 "B.SilkS" user "Ref Des/Silkscreen Bottom")
		(1 "F.Mask" user "Board Geometry/Soldermask Top")
		(3 "B.Mask" user "Board Geometry/Soldermask Bottom")
		(17 "Dwgs.User" user "User.Drawings")
		(19 "Cmts.User" user "User.Comments")
		(21 "Eco1.User" user "User.Eco1")
		(23 "Eco2.User" user "User.Eco2")
		(25 "Edge.Cuts" user "Board Geometry/Outline")
		(27 "Margin" user)
		(31 "F.CrtYd" user "Package Geometry/Place Bound Top")
		(29 "B.CrtYd" user "Package Geometry/Place Bound Bottom")
		(35 "F.Fab" user "Ref Des/Assembly Top")
		(33 "B.Fab" user "Ref Des/Assembly Bottom")
	)
	(footprint ""
		(layer "B.Cu")
		(at 4.7244 -26.797)
		(property "Reference" "C175"
			(at 0 0 0)
			(layer "B.SilkS")
			(hide yes)
			(effects
				(font
					(size 1.27 1.27)
				)
				(justify mirror)
			)
		)
		(property "Value" ""
			(at 0 0 0)
			(layer "B.Fab")
			(effects
				(font
					(size 1.27 1.27)
				)
				(justify mirror)
			)
		)
		(duplicate_pad_numbers_are_jumpers no)
		(fp_line
			(start -0.7874 -0.4064)
			(end -0.7874 0.4064)
			(stroke
				(width 0.1524)
				(type default)
			)
			(layer "B.SilkS")
		)
		(fp_line
			(start -0.7874 0.4064)
			(end 0.7874 0.4064)
			(stroke
				(width 0.1524)
				(type default)
			)
			(layer "B.SilkS")
		)
		(fp_line
			(start 0.7874 -0.4064)
			(end -0.7874 -0.4064)
			(stroke
				(width 0.1524)
				(type default)
			)
			(layer "B.SilkS")
		)
		(fp_line
			(start 0.7874 0.4064)
			(end 0.7874 -0.4064)
			(stroke
				(width 0.1524)
				(type default)
			)
			(layer "B.SilkS")
		)
		(fp_line
			(start -0.67945 -0.3048)
			(end -0.67945 0.3048)
			(stroke
				(width 0.1)
				(type default)
			)
			(layer "B.Fab")
		)
		(fp_line
			(start -0.67945 0.3048)
			(end -0.120396 0.3048)
			(stroke
				(width 0.1)
				(type default)
			)
			(layer "B.Fab")
		)
		(fp_line
			(start -0.12065 -0.3048)
			(end -0.67945 -0.3048)
			(stroke
				(width 0.1)
				(type default)
			)
			(layer "B.Fab")
		)
		(fp_line
			(start -0.12065 -0.2794)
			(end -0.12065 -0.3048)
			(stroke
				(width 0.1)
				(type default)
			)
			(layer "B.Fab")
		)
		(fp_line
			(start -0.120396 0.2794)
			(end 0.12065 0.2794)
			(stroke
				(width 0.1)
				(type default)
			)
			(layer "B.Fab")
		)
		(fp_line
			(start -0.120396 0.3048)
			(end -0.120396 0.2794)
			(stroke
				(width 0.1)
				(type default)
			)
			(layer "B.Fab")
		)
		(fp_line
			(start 0.12065 -0.305054)
			(end 0.12065 -0.2794)
			(stroke
				(width 0.1)
				(type default)
			)
			(layer "B.Fab")
		)
		(fp_line
			(start 0.12065 -0.2794)
			(end -0.12065 -0.2794)
			(stroke
				(width 0.1)
				(type default)
			)
			(layer "B.Fab")
		)
		(fp_line
			(start 0.12065 0.2794)
			(end 0.12065 0.3048)
			(stroke
				(width 0.1)
				(type default)
			)
			(layer "B.Fab")
		)
		(fp_line
			(start 0.12065 0.3048)
			(end 0.67945 0.3048)
			(stroke
				(width 0.1)
				(type default)
			)
			(layer "B.Fab")
		)
		(fp_line
			(start 0.67945 -0.305054)
			(end 0.12065 -0.305054)
			(stroke
				(width 0.1)
				(type default)
			)
			(layer "B.Fab")
		)
		(fp_line
			(start 0.67945 0.3048)
			(end 0.67945 -0.305054)
			(stroke
				(width 0.1)
				(type default)
			)
			(layer "B.Fab")
		)
		(pad "1" smd circle
			(at 0.40005 0 180)
			(size 0 0)
			(layers "B.Cu" "B.Mask" "B.Paste")
			(net "P3V3_AUX")
		)
		(pad "2" smd circle
			(at -0.40005 0 180)
			(size 0 0)
			(layers "B.Cu" "B.Mask" "B.Paste")
			(net "GND")
		)
	)
	(footprint ""
		(layer "B.Cu")
		(at 20.955 -17.907 -90)
		(property "Reference" "R54"
			(at 0 0 90)
			(layer "B.SilkS")
			(hide yes)
			(effects
				(font
					(size 1.27 1.27)
				)
				(justify mirror)
			)
		)
		(property "Value" ""
			(at 0 0 90)
			(layer "B.Fab")
			(effects
				(font
					(size 1.27 1.27)
				)
				(justify mirror)
			)
		)
		(duplicate_pad_numbers_are_jumpers no)
		(fp_line
			(start -0.7874 0.4064)
			(end 0.7874 0.4064)
			(stroke
				(width 0.1524)
				(type default)
			)
			(layer "B.SilkS")
		)
		(fp_line
			(start 0.7874 0.4064)
			(end 0.7874 -0.4064)
			(stroke
				(width 0.1524)
				(type default)
			)
			(layer "B.SilkS")
		)
		(fp_line
			(start -0.7874 -0.4064)
			(end -0.7874 0.4064)
			(stroke
				(width 0.1524)
				(type default)
			)
			(layer "B.SilkS")
		)
		(fp_line
			(start 0.7874 -0.4064)
			(end -0.7874 -0.4064)
			(stroke
				(width 0.1524)
				(type default)
			)
			(layer "B.SilkS")
		)
		(fp_line
			(start -0.67945 0.3048)
			(end -0.120396 0.3048)
			(stroke
				(width 0.1)
				(type default)
			)
			(layer "B.Fab")
		)
		(fp_line
			(start -0.120396 0.3048)
			(end -0.120396 0.2794)
			(stroke
				(width 0.1)
				(type default)
			)
			(layer "B.Fab")
		)
		(fp_line
			(start 0.12065 0.3048)
			(end 0.67945 0.3048)
			(stroke
				(width 0.1)
				(type default)
			)
			(layer "B.Fab")
		)
		(fp_line
			(start 0.67945 0.3048)
			(end 0.67945 -0.305054)
			(stroke
				(width 0.1)
				(type default)
			)
			(layer "B.Fab")
		)
		(fp_line
			(start -0.120396 0.2794)
			(end 0.12065 0.2794)
			(stroke
				(width 0.1)
				(type default)
			)
			(layer "B.Fab")
		)
		(fp_line
			(start 0.12065 0.2794)
			(end 0.12065 0.3048)
			(stroke
				(width 0.1)
				(type default)
			)
			(layer "B.Fab")
		)
		(fp_line
			(start -0.12065 -0.2794)
			(end -0.12065 -0.3048)
			(stroke
				(width 0.1)
				(type default)
			)
			(layer "B.Fab")
		)
		(fp_line
			(start 0.12065 -0.2794)
			(end -0.12065 -0.2794)
			(stroke
				(width 0.1)
				(type default)
			)
			(layer "B.Fab")
		)
		(fp_line
			(start -0.67945 -0.3048)
			(end -0.67945 0.3048)
			(stroke
				(width 0.1)
				(type default)
			)
			(layer "B.Fab")
		)
		(fp_line
			(start -0.12065 -0.3048)
			(end -0.67945 -0.3048)
			(stroke
				(width 0.1)
				(type default)
			)
			(layer "B.Fab")
		)
		(fp_line
			(start 0.12065 -0.305054)
			(end 0.12065 -0.2794)
			(stroke
				(width 0.1)
				(type default)
			)
			(layer "B.Fab")
		)
		(fp_line
			(start 0.67945 -0.305054)
			(end 0.12065 -0.305054)
			(stroke
				(width 0.1)
				(type default)
			)
			(layer "B.Fab")
		)
		(pad "1" smd circle
			(at 0.40005 0 90)
			(size 0 0)
			(layers "B.Cu" "B.Mask" "B.Paste")
			(net "SMB_BMC_ALERT16_R_N")
		)
		(pad "2" smd circle
			(at -0.40005 0 90)
			(size 0 0)
			(layers "B.Cu" "B.Mask" "B.Paste")
			(net "SMB_BMC_ALERT16_N")
		)
	)
)
